# BASEBOARD_FAB2 (Tioga Pass) — schematic netlist excerpt (pin names and nets, part order shuffled) for the footprints in the layout excerpt that follows; sources: Cadence DE-HDL packaged netlist, KiCad conversion of Wiwynn_Tioga_Pass_MB.brd

C30W2  CAP_A  0.1UF 16V 10% X7R  pkg 0402V  page 253 : A = USB3_P01_TXP ; B = USB3_P01_C_TXP
C3P13  CAP  0.22UF 16V 10% X7R  pkg 0402  page 107 : A = P3E_CPU0_PE1_SS_TXN<0> ; B = P3E_CPU0_PE1_PCH_TXN<0>
C5P9  CAP  22UF 4V 20% X6S  pkg 0805LF  page 42 : A = PVSA_CPU0 ; B = GND

(kicad_pcb
	(version 20260206)
	(generator "pcbnew")
	(generator_version "10.0")
	(general
		(thickness 1.6)
		(legacy_teardrops no)
	)
	(paper "A4")
	(title_block
		(title "Wiwynn_Tioga_Pass_MB.brd")
		(comment 1 "Tioga Pass / footprints 3984-3986 of 4770")
	)
	(layers
		(0 "F.Cu" signal "TOP")
		(4 "In1.Cu" signal "L2GND")
		(6 "In2.Cu" signal "L3")
		(8 "In3.Cu" signal "L4GND")
		(10 "In4.Cu" signal "L5")
		(12 "In5.Cu" signal "L6GND")
		(14 "In6.Cu" signal "L7VCC")
		(16 "In7.Cu" signal "L8VCC")
		(18 "In8.Cu" signal "L9GND")
		(20 "In9.Cu" signal "L10")
		(22 "In10.Cu" signal "L11GND")
		(24 "In11.Cu" signal "L12")
		(26 "In12.Cu" signal "L13GND")
		(2 "B.Cu" signal "BOTTOM")
		(9 "F.Adhes" user "F.Adhesive")
		(11 "B.Adhes" user "B.Adhesive")
		(13 "F.Paste" user "Package Geometry/Pastemask Top")
		(15 "B.Paste" user "Package Geometry/Pastemask Bottom")
		(5 "F.SilkS" user "Ref Des/Silkscreen Top")
		(7 "B.SilkS" user "Ref Des/Silkscreen Bottom")
		(1 "F.Mask" user "Board Geometry/Soldermask Top")
		(3 "B.Mask" user "Board Geometry/Soldermask Bottom")
		(17 "Dwgs.User" user "User.Drawings")
		(19 "Cmts.User" user "User.Comments")
		(21 "Eco1.User" user "User.Eco1")
		(23 "Eco2.User" user "User.Eco2")
		(25 "Edge.Cuts" user "Board Geometry/Outline")
		(27 "Margin" user)
		(31 "F.CrtYd" user "Package Geometry/Place Bound Top")
		(29 "B.CrtYd" user "Package Geometry/Place Bound Bottom")
		(35 "F.Fab" user "Ref Des/Assembly Top")
		(33 "B.Fab" user "Ref Des/Assembly Bottom")
	)
	(footprint ""
		(layer "B.Cu")
		(at 259.272024 -82.001614)
		(property "Reference" "C5P9"
			(at 0 0 0)
			(layer "B.SilkS")
			(hide yes)
			(effects
				(font
					(size 1.27 1.27)
				)
				(justify mirror)
			)
		)
		(property "Value" ""
			(at 0 0 0)
			(layer "B.Fab")
			(effects
				(font
					(size 1.27 1.27)
				)
				(justify mirror)
			)
		)
		(duplicate_pad_numbers_are_jumpers no)
		(fp_poly
			(pts
				(xy 0.7239 -0.2159) (xy -0.7239 -0.2159) (xy -0.7239 1.9939) (xy 0.7239 1.9939)
			)
			(stroke
				(width 0)
				(type default)
			)
			(fill no)
			(layer "B.CrtYd")
		)
		(fp_line
			(start -0.7239 -0.2159)
			(end 0.7239 -0.2159)
			(stroke
				(width 0.1)
				(type default)
			)
			(layer "B.Fab")
		)
		(fp_line
			(start -0.7239 1.9939)
			(end -0.7239 -0.2159)
			(stroke
				(width 0.1)
				(type default)
			)
			(layer "B.Fab")
		)
		(fp_line
			(start 0.7239 -0.2159)
			(end 0.7239 1.9939)
			(stroke
				(width 0.1)
				(type default)
			)
			(layer "B.Fab")
		)
		(fp_line
			(start 0.7239 1.9939)
			(end -0.7239 1.9939)
			(stroke
				(width 0.1)
				(type default)
			)
			(layer "B.Fab")
		)
		(pad "1" smd rect
			(at 0 0 180)
			(size 1.27 1.016)
			(layers "B.Cu" "B.Mask" "B.Paste")
			(net "PVSA_CPU0")
		)
		(pad "2" smd rect
			(at 0 1.778 180)
			(size 1.27 1.016)
			(layers "B.Cu" "B.Mask" "B.Paste")
			(net "GND")
		)
		(zone
			(layer "B.Cu")
			(hatch none 0.5)
			(connect_pads
				(clearance 0)
			)
			(min_thickness 0.25)
			(keepout
				(tracks not_allowed)
				(vias allowed)
				(pads allowed)
				(copperpour not_allowed)
				(footprints allowed)
			)
			(placement
				(enabled no)
				(sheetname "")
			)
			(fill
				(thermal_gap 0.5)
				(thermal_bridge_width 0.5)
				(island_removal_mode 0)
			)
			(polygon
				(pts
					(xy 259.907024 -81.493614) (xy 258.637024 -81.493614) (xy 258.637024 -80.731614) (xy 259.907024 -80.731614)
				)
			)
		)
	)
	(footprint ""
		(layer "B.Cu")
		(at 485.256586 -60.009532 90)
		(property "Reference" "C30W2"
			(at 0.8382 -0.67818 90)
			(unlocked yes)
			(layer "B.SilkS")
			(effects
				(font
					(size 0.4064 0.254)
					(thickness 0.1524)
				)
				(justify left mirror)
			)
		)
		(property "Value" ""
			(at 0 0 90)
			(layer "B.Fab")
			(effects
				(font
					(size 1.27 1.27)
				)
				(justify mirror)
			)
		)
		(duplicate_pad_numbers_are_jumpers no)
		(fp_poly
			(pts
				(xy -0.3048 -0.1016) (xy -0.3048 0.9906) (xy 0.3048 0.9906) (xy 0.3048 -0.1016)
			)
			(stroke
				(width 0)
				(type default)
			)
			(fill no)
			(layer "B.CrtYd")
		)
		(fp_line
			(start 0.3048 -0.1016)
			(end 0.3048 0.9906)
			(stroke
				(width 0.1)
				(type default)
			)
			(layer "B.Fab")
		)
		(fp_line
			(start -0.3048 -0.1016)
			(end 0.3048 -0.1016)
			(stroke
				(width 0.1)
				(type default)
			)
			(layer "B.Fab")
		)
		(fp_line
			(start 0.3048 0.9906)
			(end -0.3048 0.9906)
			(stroke
				(width 0.1)
				(type default)
			)
			(layer "B.Fab")
		)
		(fp_line
			(start -0.3048 0.9906)
			(end -0.3048 -0.1016)
			(stroke
				(width 0.1)
				(type default)
			)
			(layer "B.Fab")
		)
		(pad "1" smd rect
			(at 0 0 270)
			(size 0.508 0.508)
			(layers "B.Cu" "B.Mask" "B.Paste")
			(net "USB3_P01_TXP")
		)
		(pad "2" smd rect
			(at 0 0.889 270)
			(size 0.508 0.508)
			(layers "B.Cu" "B.Mask" "B.Paste")
			(net "USB3_P01_C_TXP")
		)
		(zone
			(layer "B.Cu")
			(hatch none 0.5)
			(connect_pads
				(clearance 0)
			)
			(min_thickness 0.25)
			(keepout
				(tracks allowed)
				(vias not_allowed)
				(pads allowed)
				(copperpour not_allowed)
				(footprints allowed)
			)
			(placement
				(enabled no)
				(sheetname "")
			)
			(fill
				(thermal_gap 0.5)
				(thermal_bridge_width 0.5)
				(island_removal_mode 0)
			)
			(polygon
				(pts
					(xy 485.510586 -60.263532) (xy 485.510586 -59.755532) (xy 485.891586 -59.755532) (xy 485.891586 -60.263532)
				)
			)
		)
		(zone
			(layer "B.Cu")
			(hatch none 0.5)
			(connect_pads
				(clearance 0)
			)
			(min_thickness 0.25)
			(keepout
				(tracks not_allowed)
				(vias allowed)
				(pads allowed)
				(copperpour not_allowed)
				(footprints allowed)
			)
			(placement
				(enabled no)
				(sheetname "")
			)
			(fill
				(thermal_gap 0.5)
				(thermal_bridge_width 0.5)
				(island_removal_mode 0)
			)
			(polygon
				(pts
					(xy 485.891586 -60.263532) (xy 485.891586 -59.755532) (xy 485.510586 -59.755532) (xy 485.510586 -60.263532)
				)
			)
		)
	)
	(footprint ""
		(layer "B.Cu")
		(at 340.16696 -77.694536 180)
		(property "Reference" "C3P13"
			(at 0 0 0)
			(layer "B.SilkS")
			(hide yes)
			(effects
				(font
					(size 1.27 1.27)
				)
				(justify mirror)
			)
		)
		(property "Value" ""
			(at 0 0 0)
			(layer "B.Fab")
			(effects
				(font
					(size 1.27 1.27)
				)
				(justify mirror)
			)
		)
		(duplicate_pad_numbers_are_jumpers no)
		(fp_poly
			(pts
				(xy -0.3048 -0.1016) (xy -0.3048 0.9906) (xy 0.3048 0.9906) (xy 0.3048 -0.1016)
			)
			(stroke
				(width 0)
				(type default)
			)
			(fill no)
			(layer "B.CrtYd")
		)
		(fp_line
			(start 0.3048 0.9906)
			(end -0.3048 0.9906)
			(stroke
				(width 0.1)
				(type default)
			)
			(layer "B.Fab")
		)
		(fp_line
			(start 0.3048 -0.1016)
			(end 0.3048 0.9906)
			(stroke
				(width 0.1)
				(type default)
			)
			(layer "B.Fab")
		)
		(fp_line
			(start -0.3048 0.9906)
			(end -0.3048 -0.1016)
			(stroke
				(width 0.1)
				(type default)
			)
			(layer "B.Fab")
		)
		(fp_line
			(start -0.3048 -0.1016)
			(end 0.3048 -0.1016)
			(stroke
				(width 0.1)
				(type default)
			)
			(layer "B.Fab")
		)
		(pad "1" smd rect
			(at 0 0)
			(size 0.508 0.508)
			(layers "B.Cu" "B.Mask" "B.Paste")
			(net "P3E_CPU0_PE1_SS_TXN<0>")
		)
		(pad "2" smd rect
			(at 0 0.889)
			(size 0.508 0.508)
			(layers "B.Cu" "B.Mask" "B.Paste")
			(net "P3E_CPU0_PE1_PCH_TXN<0>")
		)
		(zone
			(layer "B.Cu")
			(hatch none 0.5)
			(connect_pads
				(clearance 0)
			)
			(min_thickness 0.25)
			(keepout
				(tracks not_allowed)
				(vias allowed)
				(pads allowed)
				(copperpour not_allowed)
				(footprints allowed)
			)
			(placement
				(enabled no)
				(sheetname "")
			)
			(fill
				(thermal_gap 0.5)
				(thermal_bridge_width 0.5)
				(island_removal_mode 0)
			)
			(polygon
				(pts
					(xy 339.91296 -78.329536) (xy 340.42096 -78.329536) (xy 340.42096 -77.948536) (xy 339.91296 -77.948536)
				)
			)
		)
		(zone
			(layer "B.Cu")
			(hatch none 0.5)
			(connect_pads
				(clearance 0)
			)
			(min_thickness 0.25)
			(keepout
				(tracks allowed)
				(vias not_allowed)
				(pads allowed)
				(copperpour not_allowed)
				(footprints allowed)
			)
			(placement
				(enabled no)
				(sheetname "")
			)
			(fill
				(thermal_gap 0.5)
				(thermal_bridge_width 0.5)
				(island_removal_mode 0)
			)
			(polygon
				(pts
					(xy 339.91296 -77.948536) (xy 340.42096 -77.948536) (xy 340.42096 -78.329536) (xy 339.91296 -78.329536)
				)
			)
		)
	)
)
